FILE_TYPE = MULTI_PHYS_TABLE;

PART '74LVC1G74DP'

{========================================================================================}
:VALUE         | PART_TYPE | MATERIAL | PART_NUMBER    = STANDARD | LIFECYCLE      | PART_NUMBER   | JEDEC_TYPE        | DESCRIPTION                         | MANUFTR | MANUF_PN      | RD_CMPLS_LVL | CMPLS_LVL | FROM_PJ     | CLASS | DIP_SMD | DATA                  | EE_CHECK_LIST | FP_ECN | PSL | CREATOR | STATUS | MSD | ESD_CDM | ESD_HBM | ESD_MM | PIN_LENGTH_SHORT_PIN | PIN_LENGTH_LONG_PIN | CREATEDAY  ;
{========================================================================================}
 '74LVC1G74DP' | 'SMLF'    | 'IC'     | 'AL1G0074K01'(!) = ''       | ''               | 'AL1G0074K01' |'TSSOP8_0-65_3X3'| 'IC OTHER(8P) 74LVC1G74DP (TSSOP8)' | 'NXP'   | '74LVC1G74DP' | 'EP(V1)'     | 'EP(V1)'  | 'A7K-DENNY' | 'IC'  | ''      | 'NXP_74LVC1G74DP.pdf' | ''            | ''     | ''  | ''      | ''     | ''  | ''      | ''      | ''     | ''                   | ''                  | '20161115'
 '74LVC1G74DP' | 'SMLF'    | 'EMPTY'  | 'AL1G0074K01'(!) = ''       | ''               | 'AL1G0074K01' |'TSSOP8_0-65_3X3'| 'IC OTHER(8P) 74LVC1G74DP (TSSOP8)' | 'NXP'   | '74LVC1G74DP' | 'EP(V1)'     | 'EP(V1)'  | 'A7K-DENNY' | 'IC'  | ''      | 'NXP_74LVC1G74DP.pdf' | ''            | ''     | ''  | ''      | ''     | ''  | ''      | ''      | ''     | ''                   | ''                  | '20161115'

END_PART

END.

